FILE_TYPE = CONNECTIVITY;
{Allegro Design Entry HDL 17.2-2016 S081 (4005846) 1/11/2022}
"PAGE_NUMBER" = 43;
0"NC";
1"GND\g";
2"GND\g";
3"PWRGD_PLT_AUX_CPU1_LVT3";
4"PWRGD_PLT_AUX_CPU0_LVT3";
5"PWRGD_PLT_AUX_CPU0_LVT3_R";
6"PWRGD_PLT_AUX_CPU0_LVT3";
7"PWRGD_PLT_AUX_CPU1_LVT3_R";
8"PWRGD_PLT_AUX_CPU1_LVT3";
9"PD_JTAG_CPU1_PLD_TCK";
10"PD_JTAG_CPU0_PLD_TCK";
%"Q_RES"
"1","(425,800)","0","pure_quanta","I12";
;
PART_NUMBER"CS03322FB03"
PACK_TYPE"0402LF"
VALUE"33.2"
TOLERANCE"1%"
WATTAGE"1/16W"
MATERIAL"CHIP"
$LOCATION"R67"
CDS_LIB"pure_quanta"
CDS_LOCATION"R67"
$SEC"1"
CDS_SEC"1";
"B"
$PN"2"6;
"A"
$PN"1"5;
%"Q_RES"
"1","(425,550)","0","pure_quanta","I13";
;
PART_NUMBER"CS03322FB03"
PACK_TYPE"0402LF"
WATTAGE"1/16W"
MATERIAL"CHIP"
TOLERANCE"1%"
VALUE"33.2"
$LOCATION"R68"
CDS_LIB"pure_quanta"
CDS_LOCATION"R68"
$SEC"1"
CDS_SEC"1";
"B"
$PN"2"8;
"A"
$PN"1"7;
%"Q_RES"
"1","(475,-1875)","0","pure_quanta","I16";
;
PART_NUMBER"CS31002FB08"
TOLERANCE"1%"
VALUE"10K"
WATTAGE"1/16W"
MATERIAL"CHIP"
PACK_TYPE"0402LF"
$LOCATION"R69"
CDS_LIB"pure_quanta"
CDS_LOCATION"R69"
$SEC"1"
CDS_SEC"1";
"B"
$PN"2"1;
"A"
$PN"1"4;
%"Q_RES"
"1","(475,-2125)","0","pure_quanta","I17";
;
PART_NUMBER"CS31002FB08"
TOLERANCE"1%"
MATERIAL"CHIP"
WATTAGE"1/16W"
VALUE"10K"
PACK_TYPE"0402LF"
$LOCATION"R70"
CDS_LIB"pure_quanta"
CDS_LOCATION"R70"
$SEC"1"
CDS_SEC"1";
"B"
$PN"2"1;
"A"
$PN"1"3;
%"UNIVERSAL_GND"
"1","(1275,-2600)","0","logical_power","I20";
;
CDS_LIB"logical_power"
HDL_POWER"GND";
"A"1;
%"Q_RES"
"1","(4875,50)","0","pure_quanta","I52";
;
PART_NUMBER"CS31002FB08"
VALUE"10K"
WATTAGE"1/16W"
MATERIAL"CHIP"
TOLERANCE"1%"
PACK_TYPE"0402LF"
$LOCATION"R1226"
CDS_LIB"pure_quanta"
CDS_LOCATION"R1226"
$SEC"1"
CDS_SEC"1";
"B"
$PN"2"2;
"A"
$PN"1"10;
%"UNIVERSAL_GND"
"1","(5700,-375)","0","logical_power","I54";
;
CDS_LIB"logical_power"
HDL_POWER"GND";
"A"2;
%"Q_RES"
"1","(4875,-200)","0","pure_quanta","I56";
;
PART_NUMBER"CS31002FB08"
TOLERANCE"1%"
PACK_TYPE"0402LF"
WATTAGE"1/16W"
MATERIAL"CHIP"
VALUE"10K"
$LOCATION"R1227"
CDS_LIB"pure_quanta"
CDS_LOCATION"R1227"
$SEC"1"
CDS_SEC"1";
"B"
$PN"2"2;
"A"
$PN"1"9;
END.
